FILE_TYPE=LIBRARY_PARTS;
primitive '74LVC1G74DP';
  pin
    'CP':
      PIN_NUMBER='(1)';
      INPUT_LOAD='(-0.01,0.01)';
    'D':
      PIN_NUMBER='(2)';
      INPUT_LOAD='(-0.01,0.01)';
    '-Q':
      PIN_NUMBER='(3)';
      OUTPUT_LOAD='(1.0,-1.0)';
    'GND':
      PIN_NUMBER='(4)';
      PINUSE='POWER';
      NO_LOAD_CHECK='Both';
      NO_IO_CHECK='Both';
      NO_ASSERT_CHECK='TRUE';
      NO_DIR_CHECK='TRUE';
      ALLOW_CONNECT='TRUE';
    'VCC':
      PIN_NUMBER='(8)';
      PINUSE='POWER';
      NO_LOAD_CHECK='Both';
      NO_IO_CHECK='Both';
      NO_ASSERT_CHECK='TRUE';
      NO_DIR_CHECK='TRUE';
      ALLOW_CONNECT='TRUE';
    '-RD':
      PIN_NUMBER='(6)';
      INPUT_LOAD='(-0.01,0.01)';
    '-SD':
      PIN_NUMBER='(7)';
      INPUT_LOAD='(-0.01,0.01)';
    'Q':
      PIN_NUMBER='(5)';
      OUTPUT_LOAD='(1.0,-1.0)';
  end_pin;
  body
    PART_NAME='74LVC1G74DP';
    BODY_NAME='74LVC1G74DP';
    PHYS_DES_PREFIX='U';
    CLASS='IC';
  end_body;
end_primitive;

END.
